# T6G (Grand Teton) — schematic netlist excerpt (pin names and nets, part order shuffled) for the footprints in the layout excerpt that follows; sources: Cadence DE-HDL packaged netlist, KiCad conversion of 04192023_DAF0TMB3IC0_F0TG_MB_C_brd_V02_OCP.brd

R4155  Q_RES  4.7K 5% CHIP  pkg 0402LF  page 125 : A = P3V3_AUX ; B = PRSNT_CABLE_GPU_A1
R4131  Q_RES  54.9K 1% EMPTY  pkg 0402LF  page 125 : A = P3V3_AUX ; B = GPU_3V3IO_RSVD3_FFU

(kicad_pcb
	(version 20260206)
	(generator "pcbnew")
	(generator_version "10.0")
	(general
		(thickness 1.6)
		(legacy_teardrops no)
	)
	(paper "A4")
	(title_block
		(title "04192023_DAF0TMB3IC0_F0TG_MB_C_brd_V02_OCP.brd")
		(comment 1 "Grand Teton / footprints 830-831 of 8354")
	)
	(layers
		(0 "F.Cu" signal "TOP")
		(4 "In1.Cu" signal "GND")
		(6 "In2.Cu" signal "IN1")
		(8 "In3.Cu" signal "GND1")
		(10 "In4.Cu" signal "IN2")
		(12 "In5.Cu" signal "GND2")
		(14 "In6.Cu" signal "IN3")
		(16 "In7.Cu" signal "GND3")
		(18 "In8.Cu" signal "VCC")
		(20 "In9.Cu" signal "VCC1")
		(22 "In10.Cu" signal "GND4")
		(24 "In11.Cu" signal "IN4")
		(26 "In12.Cu" signal "GND5")
		(28 "In13.Cu" signal "IN5")
		(30 "In14.Cu" signal "GND6")
		(32 "In15.Cu" signal "IN6")
		(34 "In16.Cu" signal "GND7")
		(2 "B.Cu" signal "BOTTOM")
		(9 "F.Adhes" user "F.Adhesive")
		(11 "B.Adhes" user "B.Adhesive")
		(13 "F.Paste" user "Package Geometry/Pastemask Top")
		(15 "B.Paste" user "Package Geometry/Pastemask Bottom")
		(5 "F.SilkS" user "Ref Des/Silkscreen Top")
		(7 "B.SilkS" user "Ref Des/Silkscreen Bottom")
		(1 "F.Mask" user "Board Geometry/Soldermask Top")
		(3 "B.Mask" user "Board Geometry/Soldermask Bottom")
		(17 "Dwgs.User" user "User.Drawings")
		(19 "Cmts.User" user "User.Comments")
		(21 "Eco1.User" user "User.Eco1")
		(23 "Eco2.User" user "User.Eco2")
		(25 "Edge.Cuts" user "Board Geometry/Outline")
		(27 "Margin" user)
		(31 "F.CrtYd" user "Package Geometry/Place Bound Top")
		(29 "B.CrtYd" user "Package Geometry/Place Bound Bottom")
		(35 "F.Fab" user "Ref Des/Assembly Top")
		(33 "B.Fab" user "Ref Des/Assembly Bottom")
	)
	(footprint ""
		(layer "F.Cu")
		(at 357.20401 -418.329618 180)
		(property "Reference" "R4155"
			(at 0 0 180)
			(layer "F.SilkS")
			(hide yes)
			(effects
				(font
					(size 1.27 1.27)
				)
			)
		)
		(property "Value" ""
			(at 0 0 180)
			(layer "F.Fab")
			(effects
				(font
					(size 1.27 1.27)
				)
			)
		)
		(duplicate_pad_numbers_are_jumpers no)
		(fp_line
			(start 0.7874 0.4064)
			(end -0.7874 0.4064)
			(stroke
				(width 0.1524)
				(type default)
			)
			(layer "F.SilkS")
		)
		(fp_line
			(start 0.7874 -0.4064)
			(end 0.7874 0.4064)
			(stroke
				(width 0.1524)
				(type default)
			)
			(layer "F.SilkS")
		)
		(fp_line
			(start -0.7874 0.4064)
			(end -0.7874 -0.4064)
			(stroke
				(width 0.1524)
				(type default)
			)
			(layer "F.SilkS")
		)
		(fp_line
			(start -0.7874 -0.4064)
			(end 0.7874 -0.4064)
			(stroke
				(width 0.1524)
				(type default)
			)
			(layer "F.SilkS")
		)
		(fp_line
			(start 0.67945 0.3048)
			(end 0.120396 0.3048)
			(stroke
				(width 0.1)
				(type default)
			)
			(layer "F.Fab")
		)
		(fp_line
			(start 0.67945 -0.3048)
			(end 0.67945 0.3048)
			(stroke
				(width 0.1)
				(type default)
			)
			(layer "F.Fab")
		)
		(fp_line
			(start 0.12065 -0.2794)
			(end 0.12065 -0.3048)
			(stroke
				(width 0.1)
				(type default)
			)
			(layer "F.Fab")
		)
		(fp_line
			(start 0.12065 -0.3048)
			(end 0.67945 -0.3048)
			(stroke
				(width 0.1)
				(type default)
			)
			(layer "F.Fab")
		)
		(fp_line
			(start 0.120396 0.3048)
			(end 0.120396 0.2794)
			(stroke
				(width 0.1)
				(type default)
			)
			(layer "F.Fab")
		)
		(fp_line
			(start 0.120396 0.2794)
			(end -0.12065 0.2794)
			(stroke
				(width 0.1)
				(type default)
			)
			(layer "F.Fab")
		)
		(fp_line
			(start -0.12065 0.3048)
			(end -0.67945 0.3048)
			(stroke
				(width 0.1)
				(type default)
			)
			(layer "F.Fab")
		)
		(fp_line
			(start -0.12065 0.2794)
			(end -0.12065 0.3048)
			(stroke
				(width 0.1)
				(type default)
			)
			(layer "F.Fab")
		)
		(fp_line
			(start -0.12065 -0.2794)
			(end 0.12065 -0.2794)
			(stroke
				(width 0.1)
				(type default)
			)
			(layer "F.Fab")
		)
		(fp_line
			(start -0.12065 -0.305054)
			(end -0.12065 -0.2794)
			(stroke
				(width 0.1)
				(type default)
			)
			(layer "F.Fab")
		)
		(fp_line
			(start -0.67945 0.3048)
			(end -0.67945 -0.305054)
			(stroke
				(width 0.1)
				(type default)
			)
			(layer "F.Fab")
		)
		(fp_line
			(start -0.67945 -0.305054)
			(end -0.12065 -0.305054)
			(stroke
				(width 0.1)
				(type default)
			)
			(layer "F.Fab")
		)
		(pad "1" smd circle
			(at -0.40005 0 180)
			(size 0 0)
			(layers "F.Cu" "F.Mask" "F.Paste")
			(net "P3V3_AUX")
		)
		(pad "2" smd circle
			(at 0.40005 0 180)
			(size 0 0)
			(layers "F.Cu" "F.Mask" "F.Paste")
			(net "PRSNT_CABLE_GPU_A1")
		)
	)
	(footprint ""
		(layer "F.Cu")
		(at 304.301398 -430.2379 180)
		(property "Reference" "R4131"
			(at 0 0 180)
			(layer "F.SilkS")
			(hide yes)
			(effects
				(font
					(size 1.27 1.27)
				)
			)
		)
		(property "Value" ""
			(at 0 0 180)
			(layer "F.Fab")
			(effects
				(font
					(size 1.27 1.27)
				)
			)
		)
		(duplicate_pad_numbers_are_jumpers no)
		(fp_line
			(start 0.7874 0.4064)
			(end -0.7874 0.4064)
			(stroke
				(width 0.1524)
				(type default)
			)
			(layer "F.SilkS")
		)
		(fp_line
			(start 0.7874 -0.4064)
			(end 0.7874 0.4064)
			(stroke
				(width 0.1524)
				(type default)
			)
			(layer "F.SilkS")
		)
		(fp_line
			(start -0.7874 0.4064)
			(end -0.7874 -0.4064)
			(stroke
				(width 0.1524)
				(type default)
			)
			(layer "F.SilkS")
		)
		(fp_line
			(start -0.7874 -0.4064)
			(end 0.7874 -0.4064)
			(stroke
				(width 0.1524)
				(type default)
			)
			(layer "F.SilkS")
		)
		(fp_line
			(start 0.67945 0.3048)
			(end 0.120396 0.3048)
			(stroke
				(width 0.1)
				(type default)
			)
			(layer "F.Fab")
		)
		(fp_line
			(start 0.67945 -0.3048)
			(end 0.67945 0.3048)
			(stroke
				(width 0.1)
				(type default)
			)
			(layer "F.Fab")
		)
		(fp_line
			(start 0.12065 -0.2794)
			(end 0.12065 -0.3048)
			(stroke
				(width 0.1)
				(type default)
			)
			(layer "F.Fab")
		)
		(fp_line
			(start 0.12065 -0.3048)
			(end 0.67945 -0.3048)
			(stroke
				(width 0.1)
				(type default)
			)
			(layer "F.Fab")
		)
		(fp_line
			(start 0.120396 0.3048)
			(end 0.120396 0.2794)
			(stroke
				(width 0.1)
				(type default)
			)
			(layer "F.Fab")
		)
		(fp_line
			(start 0.120396 0.2794)
			(end -0.12065 0.2794)
			(stroke
				(width 0.1)
				(type default)
			)
			(layer "F.Fab")
		)
		(fp_line
			(start -0.12065 0.3048)
			(end -0.67945 0.3048)
			(stroke
				(width 0.1)
				(type default)
			)
			(layer "F.Fab")
		)
		(fp_line
			(start -0.12065 0.2794)
			(end -0.12065 0.3048)
			(stroke
				(width 0.1)
				(type default)
			)
			(layer "F.Fab")
		)
		(fp_line
			(start -0.12065 -0.2794)
			(end 0.12065 -0.2794)
			(stroke
				(width 0.1)
				(type default)
			)
			(layer "F.Fab")
		)
		(fp_line
			(start -0.12065 -0.305054)
			(end -0.12065 -0.2794)
			(stroke
				(width 0.1)
				(type default)
			)
			(layer "F.Fab")
		)
		(fp_line
			(start -0.67945 0.3048)
			(end -0.67945 -0.305054)
			(stroke
				(width 0.1)
				(type default)
			)
			(layer "F.Fab")
		)
		(fp_line
			(start -0.67945 -0.305054)
			(end -0.12065 -0.305054)
			(stroke
				(width 0.1)
				(type default)
			)
			(layer "F.Fab")
		)
		(pad "1" smd circle
			(at -0.40005 0 180)
			(size 0 0)
			(layers "F.Cu" "F.Mask" "F.Paste")
			(net "P3V3_AUX")
		)
		(pad "2" smd circle
			(at 0.40005 0 180)
			(size 0 0)
			(layers "F.Cu" "F.Mask" "F.Paste")
			(net "GPU_3V3IO_RSVD3_FFU")
		)
	)
)
